# S9S_MB_2U (Grand Teton) — schematic netlist excerpt (pin names and nets, part order shuffled) for the footprints in the layout excerpt that follows; sources: Cadence DE-HDL packaged netlist, KiCad conversion of 03242023_DA0F0TMBIJ0_F0T_Motherboard_J_brd_V01_OCP.brd

PC1338  Q_CAP  0.1UF 25V 10% X7R  pkg 0402  page 285 : A = GND ; B = PVCCIN_CPU1_VREF
PR50  Q_RES  12.4K 0.1% CHIP  pkg 0402LF  page 282 : A = PVNN_MAIN_CPU0_FB ; B = GND

(kicad_pcb
	(version 20260206)
	(generator "pcbnew")
	(generator_version "10.0")
	(general
		(thickness 1.6)
		(legacy_teardrops no)
	)
	(paper "A4")
	(title_block
		(title "03242023_DA0F0TMBIJ0_F0T_Motherboard_J_brd_V01_OCP.brd")
		(comment 1 "Grand Teton / footprints 1701-1702 of 6105")
	)
	(layers
		(0 "F.Cu" signal "TOP")
		(4 "In1.Cu" signal "GND")
		(6 "In2.Cu" signal "IN1")
		(8 "In3.Cu" signal "GND1")
		(10 "In4.Cu" signal "IN2")
		(12 "In5.Cu" signal "GND2")
		(14 "In6.Cu" signal "IN3")
		(16 "In7.Cu" signal "GND3")
		(18 "In8.Cu" signal "VCC")
		(20 "In9.Cu" signal "VCC1")
		(22 "In10.Cu" signal "GND4")
		(24 "In11.Cu" signal "IN4")
		(26 "In12.Cu" signal "GND5")
		(28 "In13.Cu" signal "IN5")
		(30 "In14.Cu" signal "GND6")
		(32 "In15.Cu" signal "IN6")
		(34 "In16.Cu" signal "GND7")
		(2 "B.Cu" signal "BOTTOM")
		(9 "F.Adhes" user "F.Adhesive")
		(11 "B.Adhes" user "B.Adhesive")
		(13 "F.Paste" user "Package Geometry/Pastemask Top")
		(15 "B.Paste" user "Package Geometry/Pastemask Bottom")
		(5 "F.SilkS" user "Ref Des/Silkscreen Top")
		(7 "B.SilkS" user "Ref Des/Silkscreen Bottom")
		(1 "F.Mask" user "Board Geometry/Soldermask Top")
		(3 "B.Mask" user "Board Geometry/Soldermask Bottom")
		(17 "Dwgs.User" user "User.Drawings")
		(19 "Cmts.User" user "User.Comments")
		(21 "Eco1.User" user "User.Eco1")
		(23 "Eco2.User" user "User.Eco2")
		(25 "Edge.Cuts" user "Board Geometry/Outline")
		(27 "Margin" user)
		(31 "F.CrtYd" user "Package Geometry/Place Bound Top")
		(29 "B.CrtYd" user "Package Geometry/Place Bound Bottom")
		(35 "F.Fab" user "Ref Des/Assembly Top")
		(33 "B.Fab" user "Ref Des/Assembly Bottom")
	)
	(footprint ""
		(layer "F.Cu")
		(at 432.41468 -176.61382)
		(property "Reference" "PR50"
			(at 0 0 0)
			(layer "F.SilkS")
			(hide yes)
			(effects
				(font
					(size 1.27 1.27)
				)
			)
		)
		(property "Value" ""
			(at 0 0 0)
			(layer "F.Fab")
			(effects
				(font
					(size 1.27 1.27)
				)
			)
		)
		(duplicate_pad_numbers_are_jumpers no)
		(fp_line
			(start -0.7874 -0.4064)
			(end 0.7874 -0.4064)
			(stroke
				(width 0.1524)
				(type default)
			)
			(layer "F.SilkS")
		)
		(fp_line
			(start -0.7874 0.4064)
			(end -0.7874 -0.4064)
			(stroke
				(width 0.1524)
				(type default)
			)
			(layer "F.SilkS")
		)
		(fp_line
			(start 0.7874 -0.4064)
			(end 0.7874 0.4064)
			(stroke
				(width 0.1524)
				(type default)
			)
			(layer "F.SilkS")
		)
		(fp_line
			(start 0.7874 0.4064)
			(end -0.7874 0.4064)
			(stroke
				(width 0.1524)
				(type default)
			)
			(layer "F.SilkS")
		)
		(fp_line
			(start -0.67945 -0.305054)
			(end -0.12065 -0.305054)
			(stroke
				(width 0.1)
				(type default)
			)
			(layer "F.Fab")
		)
		(fp_line
			(start -0.67945 0.3048)
			(end -0.67945 -0.305054)
			(stroke
				(width 0.1)
				(type default)
			)
			(layer "F.Fab")
		)
		(fp_line
			(start -0.12065 -0.305054)
			(end -0.12065 -0.2794)
			(stroke
				(width 0.1)
				(type default)
			)
			(layer "F.Fab")
		)
		(fp_line
			(start -0.12065 -0.2794)
			(end 0.12065 -0.2794)
			(stroke
				(width 0.1)
				(type default)
			)
			(layer "F.Fab")
		)
		(fp_line
			(start -0.12065 0.2794)
			(end -0.12065 0.3048)
			(stroke
				(width 0.1)
				(type default)
			)
			(layer "F.Fab")
		)
		(fp_line
			(start -0.12065 0.3048)
			(end -0.67945 0.3048)
			(stroke
				(width 0.1)
				(type default)
			)
			(layer "F.Fab")
		)
		(fp_line
			(start 0.120396 0.2794)
			(end -0.12065 0.2794)
			(stroke
				(width 0.1)
				(type default)
			)
			(layer "F.Fab")
		)
		(fp_line
			(start 0.120396 0.3048)
			(end 0.120396 0.2794)
			(stroke
				(width 0.1)
				(type default)
			)
			(layer "F.Fab")
		)
		(fp_line
			(start 0.12065 -0.3048)
			(end 0.67945 -0.3048)
			(stroke
				(width 0.1)
				(type default)
			)
			(layer "F.Fab")
		)
		(fp_line
			(start 0.12065 -0.2794)
			(end 0.12065 -0.3048)
			(stroke
				(width 0.1)
				(type default)
			)
			(layer "F.Fab")
		)
		(fp_line
			(start 0.67945 -0.3048)
			(end 0.67945 0.3048)
			(stroke
				(width 0.1)
				(type default)
			)
			(layer "F.Fab")
		)
		(fp_line
			(start 0.67945 0.3048)
			(end 0.120396 0.3048)
			(stroke
				(width 0.1)
				(type default)
			)
			(layer "F.Fab")
		)
		(pad "1" smd circle
			(at -0.40005 0)
			(size 0 0)
			(layers "F.Cu" "F.Mask" "F.Paste")
			(net "PVNN_MAIN_CPU0_FB")
		)
		(pad "2" smd circle
			(at 0.40005 0)
			(size 0 0)
			(layers "F.Cu" "F.Mask" "F.Paste")
			(net "GND")
		)
	)
	(footprint ""
		(layer "F.Cu")
		(at 102.355142 -338.290662 -90)
		(property "Reference" "PC1338"
			(at 0 0 270)
			(layer "F.SilkS")
			(hide yes)
			(effects
				(font
					(size 1.27 1.27)
				)
			)
		)
		(property "Value" ""
			(at 0 0 270)
			(layer "F.Fab")
			(effects
				(font
					(size 1.27 1.27)
				)
			)
		)
		(duplicate_pad_numbers_are_jumpers no)
		(fp_line
			(start -0.7874 0.4064)
			(end -0.7874 -0.4064)
			(stroke
				(width 0.1524)
				(type default)
			)
			(layer "F.SilkS")
		)
		(fp_line
			(start 0.7874 0.4064)
			(end -0.7874 0.4064)
			(stroke
				(width 0.1524)
				(type default)
			)
			(layer "F.SilkS")
		)
		(fp_line
			(start -0.7874 -0.4064)
			(end 0.7874 -0.4064)
			(stroke
				(width 0.1524)
				(type default)
			)
			(layer "F.SilkS")
		)
		(fp_line
			(start 0.7874 -0.4064)
			(end 0.7874 0.4064)
			(stroke
				(width 0.1524)
				(type default)
			)
			(layer "F.SilkS")
		)
		(fp_line
			(start -0.67945 0.3048)
			(end -0.67945 -0.305054)
			(stroke
				(width 0.1)
				(type default)
			)
			(layer "F.Fab")
		)
		(fp_line
			(start -0.12065 0.3048)
			(end -0.67945 0.3048)
			(stroke
				(width 0.1)
				(type default)
			)
			(layer "F.Fab")
		)
		(fp_line
			(start 0.120396 0.3048)
			(end 0.120396 0.2794)
			(stroke
				(width 0.1)
				(type default)
			)
			(layer "F.Fab")
		)
		(fp_line
			(start 0.67945 0.3048)
			(end 0.120396 0.3048)
			(stroke
				(width 0.1)
				(type default)
			)
			(layer "F.Fab")
		)
		(fp_line
			(start -0.12065 0.2794)
			(end -0.12065 0.3048)
			(stroke
				(width 0.1)
				(type default)
			)
			(layer "F.Fab")
		)
		(fp_line
			(start 0.120396 0.2794)
			(end -0.12065 0.2794)
			(stroke
				(width 0.1)
				(type default)
			)
			(layer "F.Fab")
		)
		(fp_line
			(start -0.12065 -0.2794)
			(end 0.12065 -0.2794)
			(stroke
				(width 0.1)
				(type default)
			)
			(layer "F.Fab")
		)
		(fp_line
			(start 0.12065 -0.2794)
			(end 0.12065 -0.3048)
			(stroke
				(width 0.1)
				(type default)
			)
			(layer "F.Fab")
		)
		(fp_line
			(start 0.12065 -0.3048)
			(end 0.67945 -0.3048)
			(stroke
				(width 0.1)
				(type default)
			)
			(layer "F.Fab")
		)
		(fp_line
			(start 0.67945 -0.3048)
			(end 0.67945 0.3048)
			(stroke
				(width 0.1)
				(type default)
			)
			(layer "F.Fab")
		)
		(fp_line
			(start -0.67945 -0.305054)
			(end -0.12065 -0.305054)
			(stroke
				(width 0.1)
				(type default)
			)
			(layer "F.Fab")
		)
		(fp_line
			(start -0.12065 -0.305054)
			(end -0.12065 -0.2794)
			(stroke
				(width 0.1)
				(type default)
			)
			(layer "F.Fab")
		)
		(pad "1" smd circle
			(at -0.40005 0 270)
			(size 0 0)
			(layers "F.Cu" "F.Mask" "F.Paste")
			(net "GND")
		)
		(pad "2" smd circle
			(at 0.40005 0 270)
			(size 0 0)
			(layers "F.Cu" "F.Mask" "F.Paste")
			(net "PVCCIN_CPU1_VREF")
		)
	)
)
